(kicad_pcb
	(version 20260206)
	(generator "pcbnew")
	(generator_version "10.0")
	(general
		(thickness 1.6)
		(legacy_teardrops no)
	)
	(paper "A4")
	(title_block
		(title "m-2 — Lightning_M.2_BRD.brd")
		(comment 1 "Lightning (Wiwynn / Facebook NVMe JBOF) / footprints 107-114 of 157")
	)
	(layers
		(0 "F.Cu" signal "TOP")
		(4 "In1.Cu" signal "L2GND")
		(6 "In2.Cu" signal "L3")
		(8 "In3.Cu" signal "L4GND")
		(10 "In4.Cu" signal "L5GND")
		(12 "In5.Cu" signal "L6")
		(14 "In6.Cu" signal "L7GND")
		(2 "B.Cu" signal "BOTTOM")
		(9 "F.Adhes" user "F.Adhesive")
		(11 "B.Adhes" user "B.Adhesive")
		(13 "F.Paste" user "Package Geometry/Pastemask Top")
		(15 "B.Paste" user "Package Geometry/Pastemask Bottom")
		(5 "F.SilkS" user "Ref Des/Silkscreen Top")
		(7 "B.SilkS" user "Ref Des/Silkscreen Bottom")
		(1 "F.Mask" user "Board Geometry/Soldermask Top")
		(3 "B.Mask" user "Board Geometry/Soldermask Bottom")
		(17 "Dwgs.User" user "User.Drawings")
		(19 "Cmts.User" user "User.Comments")
		(21 "Eco1.User" user "User.Eco1")
		(23 "Eco2.User" user "User.Eco2")
		(25 "Edge.Cuts" user "Board Geometry/Outline")
		(27 "Margin" user)
		(31 "F.CrtYd" user "Package Geometry/Place Bound Top")
		(29 "B.CrtYd" user "Package Geometry/Place Bound Bottom")
		(35 "F.Fab" user "Ref Des/Assembly Top")
		(33 "B.Fab" user "Ref Des/Assembly Bottom")
	)
	(footprint ""
		(layer "B.Cu")
		(at 25.4 -74.676)
		(property "Reference" "R57"
			(at 0 0 0)
			(layer "B.SilkS")
			(hide yes)
			(effects
				(font
					(size 1.27 1.27)
				)
				(justify mirror)
			)
		)
		(property "Value" "10KR2F-2-GP"
			(at -0.064008 -3.993896 0)
			(unlocked yes)
			(layer "B.Fab")
			(hide yes)
			(effects
				(font
					(size 1.016 1.016)
					(thickness 0.1524)
				)
				(justify mirror)
			)
		)
		(property "Device Type" "R402H16"
			(at -0.064008 -5.517896 0)
			(unlocked yes)
			(layer "B.Fab")
			(hide yes)
			(effects
				(font
					(size 1.016 1.016)
					(thickness 0.1524)
				)
				(justify mirror)
			)
		)
		(duplicate_pad_numbers_are_jumpers no)
		(fp_line
			(start -0.508 -0.9398)
			(end 0.508 -0.9398)
			(stroke
				(width 0.1524)
				(type default)
			)
			(layer "B.SilkS")
		)
		(fp_line
			(start 0.508 -0.9398)
			(end 0.508 0.9398)
			(stroke
				(width 0.1524)
				(type default)
			)
			(layer "B.SilkS")
		)
		(fp_rect
			(start 0.508 0.9398)
			(end -0.508 -0.9398)
			(stroke
				(width 0)
				(type default)
			)
			(fill no)
			(layer "B.CrtYd")
		)
		(fp_rect
			(start 0.508 0.9398)
			(end -0.508 -0.9398)
			(stroke
				(width 0)
				(type default)
			)
			(fill no)
			(layer "B.Fab")
		)
		(pad "1" smd custom
			(at 0 -0.4445 180)
			(size 0.1397 0.1397)
			(layers "B.Cu" "B.Mask" "B.Paste")
			(net "P3V3_PWR")
			(options
				(clearance outline)
				(anchor circle)
			)
			(primitives
				(gr_poly
					(pts
						(arc
							(start -0.1778 0.2794)
							(mid -0.249642 0.249642)
							(end -0.2794 0.1778)
						)
						(arc
							(start -0.2794 -0.1778)
							(mid -0.249642 -0.249642)
							(end -0.1778 -0.2794)
						)
						(arc
							(start 0.1778 -0.2794)
							(mid 0.249642 -0.249642)
							(end 0.2794 -0.1778)
						)
						(arc
							(start 0.2794 0.1778)
							(mid 0.249642 0.249642)
							(end 0.1778 0.2794)
						)
					)
					(width 0)
					(fill yes)
				)
			)
		)
		(pad "2" smd custom
			(at 0 0.4445 180)
			(size 0.1397 0.1397)
			(layers "B.Cu" "B.Mask" "B.Paste")
			(net "SSD_A1_SMB_OE")
			(options
				(clearance outline)
				(anchor circle)
			)
			(primitives
				(gr_poly
					(pts
						(arc
							(start -0.1778 0.2794)
							(mid -0.249642 0.249642)
							(end -0.2794 0.1778)
						)
						(arc
							(start -0.2794 -0.1778)
							(mid -0.249642 -0.249642)
							(end -0.1778 -0.2794)
						)
						(arc
							(start 0.1778 -0.2794)
							(mid 0.249642 -0.249642)
							(end 0.2794 -0.1778)
						)
						(arc
							(start 0.2794 0.1778)
							(mid 0.249642 0.249642)
							(end 0.1778 0.2794)
						)
					)
					(width 0)
					(fill yes)
				)
			)
		)
	)
	(footprint ""
		(layer "B.Cu")
		(at 60.579 -45.593 -90)
		(property "Reference" "C17"
			(at 0 0 90)
			(layer "B.SilkS")
			(hide yes)
			(effects
				(font
					(size 1.27 1.27)
				)
				(justify mirror)
			)
		)
		(property "Value" "SC10U6D3V5KX-4GP"
			(at 0.0762 -6.1214 270)
			(unlocked yes)
			(layer "B.Fab")
			(hide yes)
			(effects
				(font
					(size 1.016 1.016)
					(thickness 0.1524)
				)
				(justify mirror)
			)
		)
		(property "Device Type" "C805H58"
			(at 0.0762 -8.1534 270)
			(unlocked yes)
			(layer "B.Fab")
			(hide yes)
			(effects
				(font
					(size 1.016 1.016)
					(thickness 0.1524)
				)
				(justify mirror)
			)
		)
		(duplicate_pad_numbers_are_jumpers no)
		(fp_line
			(start -0.635 0)
			(end 0.635 0)
			(stroke
				(width 0.508)
				(type default)
			)
			(layer "B.SilkS")
		)
		(fp_rect
			(start 0.9652 1.778)
			(end -0.9652 -1.778)
			(stroke
				(width 0)
				(type default)
			)
			(fill no)
			(layer "B.CrtYd")
		)
		(fp_poly
			(pts
				(xy 0.9652 -1.778) (xy -0.9652 -1.778) (xy -0.9652 1.778) (xy 0.9652 1.778)
			)
			(stroke
				(width 0)
				(type default)
			)
			(fill no)
			(layer "B.Fab")
		)
		(pad "1" smd rect
			(at 0 -0.9652 90)
			(size 1.397 1.143)
			(layers "B.Cu" "B.Mask" "B.Paste")
			(net "P3V3_PWR")
		)
		(pad "2" smd rect
			(at 0 0.9652 90)
			(size 1.397 1.143)
			(layers "B.Cu" "B.Mask" "B.Paste")
			(net "GND")
		)
	)
	(footprint ""
		(layer "B.Cu")
		(at 65.913 -20.913852)
		(property "Reference" "TP9"
			(at 0 0 0)
			(layer "B.SilkS")
			(hide yes)
			(effects
				(font
					(size 1.27 1.27)
				)
				(justify mirror)
			)
		)
		(property "Value" "TPAD28-1-GP-U"
			(at -0.0508 -1.9304 0)
			(unlocked yes)
			(layer "B.Fab")
			(hide yes)
			(effects
				(font
					(size 1.016 1.016)
					(thickness 0.1524)
				)
				(justify mirror)
			)
		)
		(property "Device Type" "TPAD28-1-U"
			(at -0.0508 -3.4544 0)
			(unlocked yes)
			(layer "B.Fab")
			(hide yes)
			(effects
				(font
					(size 1.016 1.016)
					(thickness 0.1524)
				)
				(justify mirror)
			)
		)
		(duplicate_pad_numbers_are_jumpers no)
		(fp_poly
			(pts
				(arc
					(start 0.3556 0)
					(mid -0.3556 0)
					(end 0.3556 0)
				)
			)
			(stroke
				(width 0)
				(type default)
			)
			(fill no)
			(layer "B.CrtYd")
		)
		(fp_poly
			(pts
				(arc
					(start 0.9525 0)
					(mid -0.9525 0)
					(end 0.9525 0)
				)
			)
			(stroke
				(width 0)
				(type default)
			)
			(fill no)
			(layer "B.Fab")
		)
		(pad "1" smd circle
			(at 0 0 180)
			(size 0.7112 0.7112)
			(layers "B.Cu" "B.Mask" "B.Paste")
			(net "SSD_B1_MFG_DATA_TP")
		)
	)
	(footprint ""
		(layer "B.Cu")
		(at 55.450994 -77.724)
		(property "Reference" "PR26"
			(at 0 0 0)
			(layer "B.SilkS")
			(hide yes)
			(effects
				(font
					(size 1.27 1.27)
				)
				(justify mirror)
			)
		)
		(property "Value" "2KR2F-3-GP"
			(at -0.064008 -3.993896 0)
			(unlocked yes)
			(layer "B.Fab")
			(hide yes)
			(effects
				(font
					(size 1.016 1.016)
					(thickness 0.1524)
				)
				(justify mirror)
			)
		)
		(property "Device Type" "R402H16"
			(at -0.064008 -5.517896 0)
			(unlocked yes)
			(layer "B.Fab")
			(hide yes)
			(effects
				(font
					(size 1.016 1.016)
					(thickness 0.1524)
				)
				(justify mirror)
			)
		)
		(duplicate_pad_numbers_are_jumpers no)
		(fp_line
			(start -0.508 -0.9398)
			(end 0.508 -0.9398)
			(stroke
				(width 0.1524)
				(type default)
			)
			(layer "B.SilkS")
		)
		(fp_line
			(start 0.508 -0.9398)
			(end 0.508 0.9398)
			(stroke
				(width 0.1524)
				(type default)
			)
			(layer "B.SilkS")
		)
		(fp_rect
			(start 0.508 0.9398)
			(end -0.508 -0.9398)
			(stroke
				(width 0)
				(type default)
			)
			(fill no)
			(layer "B.CrtYd")
		)
		(fp_rect
			(start 0.508 0.9398)
			(end -0.508 -0.9398)
			(stroke
				(width 0)
				(type default)
			)
			(fill no)
			(layer "B.Fab")
		)
		(pad "1" smd custom
			(at 0 -0.4445 180)
			(size 0.1397 0.1397)
			(layers "B.Cu" "B.Mask" "B.Paste")
			(net "P3V3_DEV_LL")
			(options
				(clearance outline)
				(anchor circle)
			)
			(primitives
				(gr_poly
					(pts
						(arc
							(start -0.1778 0.2794)
							(mid -0.249642 0.249642)
							(end -0.2794 0.1778)
						)
						(arc
							(start -0.2794 -0.1778)
							(mid -0.249642 -0.249642)
							(end -0.1778 -0.2794)
						)
						(arc
							(start 0.1778 -0.2794)
							(mid 0.249642 -0.249642)
							(end 0.2794 -0.1778)
						)
						(arc
							(start 0.2794 0.1778)
							(mid 0.249642 0.249642)
							(end 0.1778 0.2794)
						)
					)
					(width 0)
					(fill yes)
				)
			)
		)
		(pad "2" smd custom
			(at 0 0.4445 180)
			(size 0.1397 0.1397)
			(layers "B.Cu" "B.Mask" "B.Paste")
			(net "P3V3_DEV_LL_R")
			(options
				(clearance outline)
				(anchor circle)
			)
			(primitives
				(gr_poly
					(pts
						(arc
							(start -0.1778 0.2794)
							(mid -0.249642 0.249642)
							(end -0.2794 0.1778)
						)
						(arc
							(start -0.2794 -0.1778)
							(mid -0.249642 -0.249642)
							(end -0.1778 -0.2794)
						)
						(arc
							(start 0.1778 -0.2794)
							(mid 0.249642 -0.249642)
							(end 0.2794 -0.1778)
						)
						(arc
							(start 0.2794 0.1778)
							(mid 0.249642 0.249642)
							(end 0.1778 0.2794)
						)
					)
					(width 0)
					(fill yes)
				)
			)
		)
	)
	(footprint ""
		(layer "B.Cu")
		(at 50.751994 -76.835 180)
		(property "Reference" "PR28"
			(at 0 0 0)
			(layer "B.SilkS")
			(hide yes)
			(effects
				(font
					(size 1.27 1.27)
				)
				(justify mirror)
			)
		)
		(property "Value" "10KR2F-2-GP"
			(at -0.064008 -3.993896 180)
			(unlocked yes)
			(layer "B.Fab")
			(hide yes)
			(effects
				(font
					(size 1.016 1.016)
					(thickness 0.1524)
				)
				(justify mirror)
			)
		)
		(property "Device Type" "R402H16"
			(at -0.064008 -5.517896 180)
			(unlocked yes)
			(layer "B.Fab")
			(hide yes)
			(effects
				(font
					(size 1.016 1.016)
					(thickness 0.1524)
				)
				(justify mirror)
			)
		)
		(duplicate_pad_numbers_are_jumpers no)
		(fp_line
			(start 0.508 -0.9398)
			(end 0.508 0.9398)
			(stroke
				(width 0.1524)
				(type default)
			)
			(layer "B.SilkS")
		)
		(fp_line
			(start -0.508 -0.9398)
			(end 0.508 -0.9398)
			(stroke
				(width 0.1524)
				(type default)
			)
			(layer "B.SilkS")
		)
		(fp_rect
			(start 0.508 0.9398)
			(end -0.508 -0.9398)
			(stroke
				(width 0)
				(type default)
			)
			(fill no)
			(layer "B.CrtYd")
		)
		(fp_rect
			(start 0.508 0.9398)
			(end -0.508 -0.9398)
			(stroke
				(width 0)
				(type default)
			)
			(fill no)
			(layer "B.Fab")
		)
		(pad "1" smd custom
			(at 0 -0.4445)
			(size 0.1397 0.1397)
			(layers "B.Cu" "B.Mask" "B.Paste")
			(net "AGND_P3V3_DEV")
			(options
				(clearance outline)
				(anchor circle)
			)
			(primitives
				(gr_poly
					(pts
						(arc
							(start -0.1778 0.2794)
							(mid -0.249642 0.249642)
							(end -0.2794 0.1778)
						)
						(arc
							(start -0.2794 -0.1778)
							(mid -0.249642 -0.249642)
							(end -0.1778 -0.2794)
						)
						(arc
							(start 0.1778 -0.2794)
							(mid 0.249642 -0.249642)
							(end 0.2794 -0.1778)
						)
						(arc
							(start 0.2794 0.1778)
							(mid 0.249642 0.249642)
							(end 0.1778 0.2794)
						)
					)
					(width 0)
					(fill yes)
				)
			)
		)
		(pad "2" smd custom
			(at 0 0.4445)
			(size 0.1397 0.1397)
			(layers "B.Cu" "B.Mask" "B.Paste")
			(net "P3V3_DEV_EN")
			(options
				(clearance outline)
				(anchor circle)
			)
			(primitives
				(gr_poly
					(pts
						(arc
							(start -0.1778 0.2794)
							(mid -0.249642 0.249642)
							(end -0.2794 0.1778)
						)
						(arc
							(start -0.2794 -0.1778)
							(mid -0.249642 -0.249642)
							(end -0.1778 -0.2794)
						)
						(arc
							(start 0.1778 -0.2794)
							(mid 0.249642 -0.249642)
							(end 0.2794 -0.1778)
						)
						(arc
							(start 0.2794 0.1778)
							(mid 0.249642 0.249642)
							(end 0.1778 0.2794)
						)
					)
					(width 0)
					(fill yes)
				)
			)
		)
	)
	(footprint ""
		(layer "B.Cu")
		(at 29.21 -78.74)
		(property "Reference" "R58"
			(at 0 0 0)
			(layer "B.SilkS")
			(hide yes)
			(effects
				(font
					(size 1.27 1.27)
				)
				(justify mirror)
			)
		)
		(property "Value" "47KR2F-GP"
			(at -0.064008 -3.993896 0)
			(unlocked yes)
			(layer "B.Fab")
			(hide yes)
			(effects
				(font
					(size 1.016 1.016)
					(thickness 0.1524)
				)
				(justify mirror)
			)
		)
		(property "Device Type" "R402H16"
			(at -0.064008 -5.517896 0)
			(unlocked yes)
			(layer "B.Fab")
			(hide yes)
			(effects
				(font
					(size 1.016 1.016)
					(thickness 0.1524)
				)
				(justify mirror)
			)
		)
		(duplicate_pad_numbers_are_jumpers no)
		(fp_line
			(start -0.508 -0.9398)
			(end 0.508 -0.9398)
			(stroke
				(width 0.1524)
				(type default)
			)
			(layer "B.SilkS")
		)
		(fp_line
			(start 0.508 -0.9398)
			(end 0.508 0.9398)
			(stroke
				(width 0.1524)
				(type default)
			)
			(layer "B.SilkS")
		)
		(fp_rect
			(start 0.508 0.9398)
			(end -0.508 -0.9398)
			(stroke
				(width 0)
				(type default)
			)
			(fill no)
			(layer "B.CrtYd")
		)
		(fp_rect
			(start 0.508 0.9398)
			(end -0.508 -0.9398)
			(stroke
				(width 0)
				(type default)
			)
			(fill no)
			(layer "B.Fab")
		)
		(pad "1" smd custom
			(at 0 -0.4445 180)
			(size 0.1397 0.1397)
			(layers "B.Cu" "B.Mask" "B.Paste")
			(net "Z50_SSD_A1_SMB_DATA_R")
			(options
				(clearance outline)
				(anchor circle)
			)
			(primitives
				(gr_poly
					(pts
						(arc
							(start -0.1778 0.2794)
							(mid -0.249642 0.249642)
							(end -0.2794 0.1778)
						)
						(arc
							(start -0.2794 -0.1778)
							(mid -0.249642 -0.249642)
							(end -0.1778 -0.2794)
						)
						(arc
							(start 0.1778 -0.2794)
							(mid 0.249642 -0.249642)
							(end 0.2794 -0.1778)
						)
						(arc
							(start 0.2794 0.1778)
							(mid 0.249642 0.249642)
							(end 0.1778 0.2794)
						)
					)
					(width 0)
					(fill yes)
				)
			)
		)
		(pad "2" smd custom
			(at 0 0.4445 180)
			(size 0.1397 0.1397)
			(layers "B.Cu" "B.Mask" "B.Paste")
			(net "P3V3_DPB")
			(options
				(clearance outline)
				(anchor circle)
			)
			(primitives
				(gr_poly
					(pts
						(arc
							(start -0.1778 0.2794)
							(mid -0.249642 0.249642)
							(end -0.2794 0.1778)
						)
						(arc
							(start -0.2794 -0.1778)
							(mid -0.249642 -0.249642)
							(end -0.1778 -0.2794)
						)
						(arc
							(start 0.1778 -0.2794)
							(mid 0.249642 -0.249642)
							(end 0.2794 -0.1778)
						)
						(arc
							(start 0.2794 0.1778)
							(mid 0.249642 0.249642)
							(end 0.1778 0.2794)
						)
					)
					(width 0)
					(fill yes)
				)
			)
		)
	)
	(footprint ""
		(layer "B.Cu")
		(at 25.146 -71.755 180)
		(property "Reference" "R36"
			(at 0 0 0)
			(layer "B.SilkS")
			(hide yes)
			(effects
				(font
					(size 1.27 1.27)
				)
				(justify mirror)
			)
		)
		(property "Value" "47KR2F-GP"
			(at -0.064008 -3.993896 180)
			(unlocked yes)
			(layer "B.Fab")
			(hide yes)
			(effects
				(font
					(size 1.016 1.016)
					(thickness 0.1524)
				)
				(justify mirror)
			)
		)
		(property "Device Type" "R402H16"
			(at -0.064008 -5.517896 180)
			(unlocked yes)
			(layer "B.Fab")
			(hide yes)
			(effects
				(font
					(size 1.016 1.016)
					(thickness 0.1524)
				)
				(justify mirror)
			)
		)
		(duplicate_pad_numbers_are_jumpers no)
		(fp_line
			(start 0.508 -0.9398)
			(end 0.508 0.9398)
			(stroke
				(width 0.1524)
				(type default)
			)
			(layer "B.SilkS")
		)
		(fp_line
			(start -0.508 -0.9398)
			(end 0.508 -0.9398)
			(stroke
				(width 0.1524)
				(type default)
			)
			(layer "B.SilkS")
		)
		(fp_rect
			(start 0.508 0.9398)
			(end -0.508 -0.9398)
			(stroke
				(width 0)
				(type default)
			)
			(fill no)
			(layer "B.CrtYd")
		)
		(fp_rect
			(start 0.508 0.9398)
			(end -0.508 -0.9398)
			(stroke
				(width 0)
				(type default)
			)
			(fill no)
			(layer "B.Fab")
		)
		(pad "1" smd custom
			(at 0 -0.4445)
			(size 0.1397 0.1397)
			(layers "B.Cu" "B.Mask" "B.Paste")
			(net "Z50_SSD_A1_SMB_DATA")
			(options
				(clearance outline)
				(anchor circle)
			)
			(primitives
				(gr_poly
					(pts
						(arc
							(start -0.1778 0.2794)
							(mid -0.249642 0.249642)
							(end -0.2794 0.1778)
						)
						(arc
							(start -0.2794 -0.1778)
							(mid -0.249642 -0.249642)
							(end -0.1778 -0.2794)
						)
						(arc
							(start 0.1778 -0.2794)
							(mid 0.249642 -0.249642)
							(end 0.2794 -0.1778)
						)
						(arc
							(start 0.2794 0.1778)
							(mid 0.249642 0.249642)
							(end 0.1778 0.2794)
						)
					)
					(width 0)
					(fill yes)
				)
			)
		)
		(pad "2" smd custom
			(at 0 0.4445)
			(size 0.1397 0.1397)
			(layers "B.Cu" "B.Mask" "B.Paste")
			(net "P1V8_PWR")
			(options
				(clearance outline)
				(anchor circle)
			)
			(primitives
				(gr_poly
					(pts
						(arc
							(start -0.1778 0.2794)
							(mid -0.249642 0.249642)
							(end -0.2794 0.1778)
						)
						(arc
							(start -0.2794 -0.1778)
							(mid -0.249642 -0.249642)
							(end -0.1778 -0.2794)
						)
						(arc
							(start 0.1778 -0.2794)
							(mid 0.249642 -0.249642)
							(end 0.2794 -0.1778)
						)
						(arc
							(start 0.2794 0.1778)
							(mid 0.249642 0.249642)
							(end 0.1778 0.2794)
						)
					)
					(width 0)
					(fill yes)
				)
			)
		)
	)
	(footprint ""
		(layer "B.Cu")
		(at 64.008 -20.913852)
		(property "Reference" "TP8"
			(at 0 0 0)
			(layer "B.SilkS")
			(hide yes)
			(effects
				(font
					(size 1.27 1.27)
				)
				(justify mirror)
			)
		)
		(property "Value" "TPAD28-1-GP-U"
			(at -0.0508 -1.9304 0)
			(unlocked yes)
			(layer "B.Fab")
			(hide yes)
			(effects
				(font
					(size 1.016 1.016)
					(thickness 0.1524)
				)
				(justify mirror)
			)
		)
		(property "Device Type" "TPAD28-1-U"
			(at -0.0508 -3.4544 0)
			(unlocked yes)
			(layer "B.Fab")
			(hide yes)
			(effects
				(font
					(size 1.016 1.016)
					(thickness 0.1524)
				)
				(justify mirror)
			)
		)
		(duplicate_pad_numbers_are_jumpers no)
		(fp_poly
			(pts
				(arc
					(start 0.3556 0)
					(mid -0.3556 0)
					(end 0.3556 0)
				)
			)
			(stroke
				(width 0)
				(type default)
			)
			(fill no)
			(layer "B.CrtYd")
		)
		(fp_poly
			(pts
				(arc
					(start 0.9525 0)
					(mid -0.9525 0)
					(end 0.9525 0)
				)
			)
			(stroke
				(width 0)
				(type default)
			)
			(fill no)
			(layer "B.Fab")
		)
		(pad "1" smd circle
			(at 0 0 180)
			(size 0.7112 0.7112)
			(layers "B.Cu" "B.Mask" "B.Paste")
			(net "SSD_B1_MFG_CLK_TP")
		)
	)
)
